(kicad_pcb
	(version 20221018)
	(generator pcbnew)
	(general
    (thickness 1.62)
  )
	(paper "A4")
	(title_block
    (title "ECP5 - Datacenter Secure Control Module (DC-SCM)")
    (date "2024-07-01")
    (rev "1.2.1")
		(comment 9 "footprints 264-271 of 506")
	)
	(layers
    (0 "F.Cu" signal)
    (1 "In1.Cu" power)
    (2 "In2.Cu" signal)
    (3 "In3.Cu" power)
    (4 "In4.Cu" power)
    (5 "In5.Cu" signal)
    (6 "In6.Cu" power)
    (31 "B.Cu" signal)
    (32 "B.Adhes" user "B.Adhesive")
    (33 "F.Adhes" user "F.Adhesive")
    (34 "B.Paste" user)
    (35 "F.Paste" user)
    (36 "B.SilkS" user "B.Silkscreen")
    (37 "F.SilkS" user "F.Silkscreen")
    (38 "B.Mask" user)
    (39 "F.Mask" user)
    (40 "Dwgs.User" user "User.Drawings")
    (41 "Cmts.User" user "User.Comments")
    (42 "Eco1.User" user "User.Eco1")
    (43 "Eco2.User" user "User.Eco2")
    (44 "Edge.Cuts" user)
    (45 "Margin" user)
    (46 "B.CrtYd" user "B.Courtyard")
    (47 "F.CrtYd" user "F.Courtyard")
    (48 "B.Fab" user)
    (49 "F.Fab" user)
  )
	(footprint "antmicro-footprints:C_0603_1608Metric" (layer "B.Cu")
    (at 99.65 132.55 90)
    (descr "Capacitor SMD 0603")
    (tags "capacitor 0603")
    (property "Author" "Antmicro")
    (property "Dielectric" "")
    (property "License" "Apache-2.0")
    (property "MPN" "GRM188R60J476ME15D")
    (property "Manufacturer" "Murata")
    (property "Public" "False")
    (property "Sheetfile" "fpga-power-supply.kicad_sch")
    (property "Sheetname" "FPGA power supply")
    (property "Val" "47u")
    (property "Voltage" "")
    (property "ki_description" "SMD Multilayer Ceramic Capacitor, 47 µF, 6.3 V, 0603 [1608 Metric], ± 20%, X5R, GRM Series")
    (property "ki_keywords" "0603, SMT, CAPACITOR, PASSIVE, CERAMIC, MLCC")
    (attr smd)
    (fp_text reference "C133" (at -20.385 1.25 90) (layer "B.SilkS")
        (effects (font (size 0.7 0.7) (thickness 0.127)) (justify mirror))
    )
    (fp_text value "C_47u_0603" (at 0 -1.9 90) (layer "B.Fab")
        (effects (font (size 1 1) (thickness 0.15)) (justify mirror))
    )
    (fp_text user "${REFERENCE}" (at -1.682 -3.895 270) (layer "B.Fab") hide
        (effects (font (size 0.7 0.7) (thickness 0.15)) (justify left bottom mirror))
    )
    (fp_text user "Author: Antmicro" (at -1.682 -4.894 270) (layer "B.Fab") hide
        (effects (font (size 0.7 0.7) (thickness 0.15)) (justify left bottom mirror))
    )
    (fp_text user "License: Apache-2.0" (at -1.682 -5.895 270) (layer "B.Fab") hide
        (effects (font (size 0.7 0.7) (thickness 0.15)) (justify left bottom mirror))
    )
    (fp_line (start -0.15 -0.4) (end 0.15 -0.4)
      (stroke (width 0.15) (type solid)) (layer "B.SilkS"))
    (fp_line (start -0.15 0.4) (end 0.15 0.4)
      (stroke (width 0.15) (type solid)) (layer "B.SilkS"))
    (fp_rect (start -1.25 0.65) (end 1.25 -0.65)
      (stroke (width 0.05) (type solid)) (fill none) (layer "B.CrtYd"))
    (fp_rect (start -0.8 0.4) (end 0.8 -0.4)
      (stroke (width 0.15) (type solid)) (fill none) (layer "B.Fab"))
    (pad "1" smd roundrect (at -0.7 0 90) (size 0.8 1) (layers "B.Cu" "B.Paste" "B.Mask") (roundrect_rratio 0.2)
      (net 1 "GND") (pintype "passive"))
    (pad "2" smd roundrect (at 0.7 0 90) (size 0.8 1) (layers "B.Cu" "B.Paste" "B.Mask") (roundrect_rratio 0.2)
      (net 302 "/FPGA power supply/VCCA0") (pintype "passive"))
  )
	(footprint "antmicro-footprints:C_0402_1005Metric" (layer "B.Cu")
    (at 96.85 130.8)
    (descr "Capacitor SMD 0402")
    (tags "capacitor SMD 0402")
    (property "Author" "Antmicro")
    (property "Dielectric" "")
    (property "License" "Apache-2.0")
    (property "MPN" "GRM155R61A475MEAAD")
    (property "Manufacturer" "Murata")
    (property "Public" "False")
    (property "Sheetfile" "fpga-power-supply.kicad_sch")
    (property "Sheetname" "FPGA power supply")
    (property "Val" "4u7")
    (property "Voltage" "")
    (property "ki_description" "SMD Multilayer Ceramic Capacitor, 4.7 µF, 10 V, 0402 [1005 Metric], ± 20%, X5R, GRM Series")
    (property "ki_keywords" "0402, SMT, CAPACITOR, PASSIVE")
    (attr smd)
    (fp_text reference "C134" (at -2.74 0.085) (layer "B.SilkS")
        (effects (font (size 0.7 0.7) (thickness 0.127)) (justify mirror))
    )
    (fp_text value "C_4u7_0402" (at 0 -1.17) (layer "B.Fab")
        (effects (font (size 1 1) (thickness 0.15)) (justify mirror))
    )
    (fp_text user "${REFERENCE}" (at 0 0) (layer "B.Fab")
        (effects (font (size 0.25 0.25) (thickness 0.04)) (justify mirror))
    )
    (fp_text user "License: Apache-2.0" (at -0.939 -5.799 180) (layer "B.Fab") hide
        (effects (font (size 0.7 0.7) (thickness 0.15)) (justify left bottom mirror))
    )
    (fp_text user "Author: Antmicro" (at -0.939 -3.399 180) (layer "B.Fab") hide
        (effects (font (size 0.7 0.7) (thickness 0.15)) (justify left bottom mirror))
    )
    (fp_rect (start -0.925 0.47) (end 0.925 -0.47)
      (stroke (width 0.05) (type default)) (fill none) (layer "B.CrtYd"))
    (fp_line (start -0.494 -0.248) (end -0.494 0.25)
      (stroke (width 0.15) (type solid)) (layer "B.Fab"))
    (fp_line (start -0.494 0.25) (end 0.504 0.25)
      (stroke (width 0.15) (type solid)) (layer "B.Fab"))
    (fp_line (start 0.504 -0.248) (end -0.494 -0.248)
      (stroke (width 0.15) (type solid)) (layer "B.Fab"))
    (fp_line (start 0.504 0.25) (end 0.504 -0.248)
      (stroke (width 0.15) (type solid)) (layer "B.Fab"))
    (pad "1" smd roundrect (at -0.48 0) (size 0.59 0.64) (layers "B.Cu" "B.Paste" "B.Mask") (roundrect_rratio 0.25)
      (net 1 "GND") (pintype "passive"))
    (pad "2" smd roundrect (at 0.48 0) (size 0.59 0.64) (layers "B.Cu" "B.Paste" "B.Mask") (roundrect_rratio 0.25)
      (net 302 "/FPGA power supply/VCCA0") (pintype "passive"))
  )
	(footprint "antmicro-footprints:C_0402_1005Metric" (layer "B.Cu")
    (at 96.85 129.8)
    (descr "Capacitor SMD 0402")
    (tags "capacitor SMD 0402")
    (property "Author" "Antmicro")
    (property "Dielectric" "")
    (property "License" "Apache-2.0")
    (property "MPN" "C1005X5R1E474M050BB")
    (property "Manufacturer" "TDK")
    (property "Public" "False")
    (property "Sheetfile" "fpga-power-supply.kicad_sch")
    (property "Sheetname" "FPGA power supply")
    (property "Val" "470n")
    (property "Voltage" "")
    (property "ki_description" "SMD Multilayer Ceramic Capacitor, 0.47 µF, 25 V, 0402 [1005 Metric], ± 20%, X5R, C")
    (property "ki_keywords" "0402, SMT, CAPACITOR, PASSIVE, CERAMIC, MLCC")
    (attr smd)
    (fp_text reference "C136" (at -2.17 -0.305) (layer "B.SilkS")
        (effects (font (size 0.7 0.7) (thickness 0.127)) (justify mirror))
    )
    (fp_text value "C_470n_0402" (at 0 -1.17) (layer "B.Fab")
        (effects (font (size 1 1) (thickness 0.15)) (justify mirror))
    )
    (fp_text user "Author: Antmicro" (at -0.939 -3.399 180) (layer "B.Fab") hide
        (effects (font (size 0.7 0.7) (thickness 0.15)) (justify left bottom mirror))
    )
    (fp_text user "${REFERENCE}" (at 0 0) (layer "B.Fab")
        (effects (font (size 0.25 0.25) (thickness 0.04)) (justify mirror))
    )
    (fp_text user "License: Apache-2.0" (at -0.939 -5.799 180) (layer "B.Fab") hide
        (effects (font (size 0.7 0.7) (thickness 0.15)) (justify left bottom mirror))
    )
    (fp_rect (start -0.925 0.47) (end 0.925 -0.47)
      (stroke (width 0.05) (type default)) (fill none) (layer "B.CrtYd"))
    (fp_line (start -0.494 -0.248) (end -0.494 0.25)
      (stroke (width 0.15) (type solid)) (layer "B.Fab"))
    (fp_line (start -0.494 0.25) (end 0.504 0.25)
      (stroke (width 0.15) (type solid)) (layer "B.Fab"))
    (fp_line (start 0.504 -0.248) (end -0.494 -0.248)
      (stroke (width 0.15) (type solid)) (layer "B.Fab"))
    (fp_line (start 0.504 0.25) (end 0.504 -0.248)
      (stroke (width 0.15) (type solid)) (layer "B.Fab"))
    (pad "1" smd roundrect (at -0.48 0) (size 0.59 0.64) (layers "B.Cu" "B.Paste" "B.Mask") (roundrect_rratio 0.25)
      (net 1 "GND") (pintype "passive"))
    (pad "2" smd roundrect (at 0.48 0) (size 0.59 0.64) (layers "B.Cu" "B.Paste" "B.Mask") (roundrect_rratio 0.25)
      (net 302 "/FPGA power supply/VCCA0") (pintype "passive"))
  )
	(footprint "antmicro-footprints:C_0402_1005Metric" (layer "B.Cu")
    (at 102.335 129.25 180)
    (descr "Capacitor SMD 0402")
    (tags "capacitor SMD 0402")
    (property "Author" "Antmicro")
    (property "Dielectric" "X5R")
    (property "License" "Apache-2.0")
    (property "MPN" "GRM155R61H104KE14D")
    (property "Manufacturer" "Murata")
    (property "Public" "False")
    (property "Sheetfile" "fpga-power-supply.kicad_sch")
    (property "Sheetname" "FPGA power supply")
    (property "Val" "100n")
    (property "Voltage" "50V")
    (property "ki_description" "SMD Multilayer Ceramic Capacitor, 0.1 µF, 50 V, 0402 [1005 Metric], ± 10%, X5R, GRM Series")
    (property "ki_keywords" "0402, SMT, CAPACITOR, PASSIVE, CERAMIC, MLCC")
    (attr smd)
    (fp_text reference "C137" (at -0.145 -20.705) (layer "B.SilkS")
        (effects (font (size 0.7 0.7) (thickness 0.127)) (justify mirror))
    )
    (fp_text value "C_100n_0402" (at 0 -1.17) (layer "B.Fab")
        (effects (font (size 1 1) (thickness 0.15)) (justify mirror))
    )
    (fp_text user "${REFERENCE}" (at 0 0) (layer "B.Fab")
        (effects (font (size 0.25 0.25) (thickness 0.04)) (justify mirror))
    )
    (fp_text user "License: Apache-2.0" (at -0.939 -5.799) (layer "B.Fab") hide
        (effects (font (size 0.7 0.7) (thickness 0.15)) (justify left bottom mirror))
    )
    (fp_text user "Author: Antmicro" (at -0.939 -3.399) (layer "B.Fab") hide
        (effects (font (size 0.7 0.7) (thickness 0.15)) (justify left bottom mirror))
    )
    (fp_rect (start -0.925 0.47) (end 0.925 -0.47)
      (stroke (width 0.05) (type default)) (fill none) (layer "B.CrtYd"))
    (fp_line (start -0.494 -0.248) (end -0.494 0.25)
      (stroke (width 0.15) (type solid)) (layer "B.Fab"))
    (fp_line (start -0.494 0.25) (end 0.504 0.25)
      (stroke (width 0.15) (type solid)) (layer "B.Fab"))
    (fp_line (start 0.504 -0.248) (end -0.494 -0.248)
      (stroke (width 0.15) (type solid)) (layer "B.Fab"))
    (fp_line (start 0.504 0.25) (end 0.504 -0.248)
      (stroke (width 0.15) (type solid)) (layer "B.Fab"))
    (pad "1" smd roundrect (at -0.48 0 180) (size 0.59 0.64) (layers "B.Cu" "B.Paste" "B.Mask") (roundrect_rratio 0.25)
      (net 1 "GND") (pintype "passive"))
    (pad "2" smd roundrect (at 0.48 0 180) (size 0.59 0.64) (layers "B.Cu" "B.Paste" "B.Mask") (roundrect_rratio 0.25)
      (net 302 "/FPGA power supply/VCCA0") (pintype "passive"))
  )
	(footprint "antmicro-footprints:C_0402_1005Metric" (layer "B.Cu")
    (at 98.4 132.25 90)
    (descr "Capacitor SMD 0402")
    (tags "capacitor SMD 0402")
    (property "Author" "Antmicro")
    (property "Dielectric" "X7R")
    (property "License" "Apache-2.0")
    (property "MPN" "GRM155R71H103KA88D")
    (property "Manufacturer" "Murata")
    (property "Public" "False")
    (property "Sheetfile" "fpga-power-supply.kicad_sch")
    (property "Sheetname" "FPGA power supply")
    (property "Val" "10n")
    (property "Voltage" "50V")
    (property "ki_description" "SMD Multilayer Ceramic Capacitor, 10000 pF, 50 V, 0402 [1005 Metric], ± 10%, X7R, GRM Series")
    (property "ki_keywords" "0402, SMT, CAPACITOR, PASSIVE")
    (attr smd)
    (fp_text reference "C138" (at -20.685 1.5 90) (layer "B.SilkS")
        (effects (font (size 0.7 0.7) (thickness 0.127)) (justify mirror))
    )
    (fp_text value "C_10n_0402" (at 0 -1.17 90) (layer "B.Fab")
        (effects (font (size 1 1) (thickness 0.15)) (justify mirror))
    )
    (fp_text user "Author: Antmicro" (at -0.939 -3.399 270) (layer "B.Fab") hide
        (effects (font (size 0.7 0.7) (thickness 0.15)) (justify left bottom mirror))
    )
    (fp_text user "License: Apache-2.0" (at -0.939 -5.799 270) (layer "B.Fab") hide
        (effects (font (size 0.7 0.7) (thickness 0.15)) (justify left bottom mirror))
    )
    (fp_text user "${REFERENCE}" (at 0 0 90) (layer "B.Fab")
        (effects (font (size 0.25 0.25) (thickness 0.04)) (justify mirror))
    )
    (fp_rect (start -0.925 0.47) (end 0.925 -0.47)
      (stroke (width 0.05) (type default)) (fill none) (layer "B.CrtYd"))
    (fp_line (start -0.494 -0.248) (end -0.494 0.25)
      (stroke (width 0.15) (type solid)) (layer "B.Fab"))
    (fp_line (start -0.494 0.25) (end 0.504 0.25)
      (stroke (width 0.15) (type solid)) (layer "B.Fab"))
    (fp_line (start 0.504 -0.248) (end -0.494 -0.248)
      (stroke (width 0.15) (type solid)) (layer "B.Fab"))
    (fp_line (start 0.504 0.25) (end 0.504 -0.248)
      (stroke (width 0.15) (type solid)) (layer "B.Fab"))
    (pad "1" smd roundrect (at -0.48 0 90) (size 0.59 0.64) (layers "B.Cu" "B.Paste" "B.Mask") (roundrect_rratio 0.25)
      (net 1 "GND") (pintype "passive"))
    (pad "2" smd roundrect (at 0.48 0 90) (size 0.59 0.64) (layers "B.Cu" "B.Paste" "B.Mask") (roundrect_rratio 0.25)
      (net 302 "/FPGA power supply/VCCA0") (pintype "passive"))
  )
	(footprint "antmicro-footprints:C_0402_1005Metric" (layer "B.Cu")
    (at 100.9 132.25 90)
    (descr "Capacitor SMD 0402")
    (tags "capacitor SMD 0402")
    (property "Author" "Antmicro")
    (property "Dielectric" "X7R")
    (property "License" "Apache-2.0")
    (property "MPN" "GRM155R71H103KA88D")
    (property "Manufacturer" "Murata")
    (property "Public" "False")
    (property "Sheetfile" "fpga-power-supply.kicad_sch")
    (property "Sheetname" "FPGA power supply")
    (property "Val" "10n")
    (property "Voltage" "50V")
    (property "ki_description" "SMD Multilayer Ceramic Capacitor, 10000 pF, 50 V, 0402 [1005 Metric], ± 10%, X7R, GRM Series")
    (property "ki_keywords" "0402, SMT, CAPACITOR, PASSIVE")
    (attr smd)
    (fp_text reference "C143" (at -20.675 0.98 90) (layer "B.SilkS")
        (effects (font (size 0.7 0.7) (thickness 0.127)) (justify mirror))
    )
    (fp_text value "C_10n_0402" (at 0 -1.17 90) (layer "B.Fab")
        (effects (font (size 1 1) (thickness 0.15)) (justify mirror))
    )
    (fp_text user "License: Apache-2.0" (at -0.939 -5.799 270) (layer "B.Fab") hide
        (effects (font (size 0.7 0.7) (thickness 0.15)) (justify left bottom mirror))
    )
    (fp_text user "${REFERENCE}" (at 0 0 90) (layer "B.Fab")
        (effects (font (size 0.25 0.25) (thickness 0.04)) (justify mirror))
    )
    (fp_text user "Author: Antmicro" (at -0.939 -3.399 270) (layer "B.Fab") hide
        (effects (font (size 0.7 0.7) (thickness 0.15)) (justify left bottom mirror))
    )
    (fp_rect (start -0.925 0.47) (end 0.925 -0.47)
      (stroke (width 0.05) (type default)) (fill none) (layer "B.CrtYd"))
    (fp_line (start -0.494 -0.248) (end -0.494 0.25)
      (stroke (width 0.15) (type solid)) (layer "B.Fab"))
    (fp_line (start -0.494 0.25) (end 0.504 0.25)
      (stroke (width 0.15) (type solid)) (layer "B.Fab"))
    (fp_line (start 0.504 -0.248) (end -0.494 -0.248)
      (stroke (width 0.15) (type solid)) (layer "B.Fab"))
    (fp_line (start 0.504 0.25) (end 0.504 -0.248)
      (stroke (width 0.15) (type solid)) (layer "B.Fab"))
    (pad "1" smd roundrect (at -0.48 0 90) (size 0.59 0.64) (layers "B.Cu" "B.Paste" "B.Mask") (roundrect_rratio 0.25)
      (net 1 "GND") (pintype "passive"))
    (pad "2" smd roundrect (at 0.48 0 90) (size 0.59 0.64) (layers "B.Cu" "B.Paste" "B.Mask") (roundrect_rratio 0.25)
      (net 302 "/FPGA power supply/VCCA0") (pintype "passive"))
  )
	(footprint "antmicro-footprints:C_0402_1005Metric" (layer "B.Cu")
    (at 97.4 132.25 90)
    (descr "Capacitor SMD 0402")
    (tags "capacitor SMD 0402")
    (property "Author" "Antmicro")
    (property "Dielectric" "X7R")
    (property "License" "Apache-2.0")
    (property "MPN" "GRM155R71H103KA88D")
    (property "Manufacturer" "Murata")
    (property "Public" "False")
    (property "Sheetfile" "fpga-power-supply.kicad_sch")
    (property "Sheetname" "FPGA power supply")
    (property "Val" "10n")
    (property "Voltage" "50V")
    (property "ki_description" "SMD Multilayer Ceramic Capacitor, 10000 pF, 50 V, 0402 [1005 Metric], ± 10%, X7R, GRM Series")
    (property "ki_keywords" "0402, SMT, CAPACITOR, PASSIVE")
    (attr smd)
    (fp_text reference "C145" (at -20.685 1.47 90) (layer "B.SilkS")
        (effects (font (size 0.7 0.7) (thickness 0.127)) (justify mirror))
    )
    (fp_text value "C_10n_0402" (at 0 -1.17 90) (layer "B.Fab")
        (effects (font (size 1 1) (thickness 0.15)) (justify mirror))
    )
    (fp_text user "Author: Antmicro" (at -0.939 -3.399 270) (layer "B.Fab") hide
        (effects (font (size 0.7 0.7) (thickness 0.15)) (justify left bottom mirror))
    )
    (fp_text user "License: Apache-2.0" (at -0.939 -5.799 270) (layer "B.Fab") hide
        (effects (font (size 0.7 0.7) (thickness 0.15)) (justify left bottom mirror))
    )
    (fp_text user "${REFERENCE}" (at 0 0 90) (layer "B.Fab")
        (effects (font (size 0.25 0.25) (thickness 0.04)) (justify mirror))
    )
    (fp_rect (start -0.925 0.47) (end 0.925 -0.47)
      (stroke (width 0.05) (type default)) (fill none) (layer "B.CrtYd"))
    (fp_line (start -0.494 -0.248) (end -0.494 0.25)
      (stroke (width 0.15) (type solid)) (layer "B.Fab"))
    (fp_line (start -0.494 0.25) (end 0.504 0.25)
      (stroke (width 0.15) (type solid)) (layer "B.Fab"))
    (fp_line (start 0.504 -0.248) (end -0.494 -0.248)
      (stroke (width 0.15) (type solid)) (layer "B.Fab"))
    (fp_line (start 0.504 0.25) (end 0.504 -0.248)
      (stroke (width 0.15) (type solid)) (layer "B.Fab"))
    (pad "1" smd roundrect (at -0.48 0 90) (size 0.59 0.64) (layers "B.Cu" "B.Paste" "B.Mask") (roundrect_rratio 0.25)
      (net 1 "GND") (pintype "passive"))
    (pad "2" smd roundrect (at 0.48 0 90) (size 0.59 0.64) (layers "B.Cu" "B.Paste" "B.Mask") (roundrect_rratio 0.25)
      (net 302 "/FPGA power supply/VCCA0") (pintype "passive"))
  )
	(footprint "antmicro-footprints:C_0402_1005Metric" (layer "B.Cu")
    (at 103.55 127.4 90)
    (descr "Capacitor SMD 0402")
    (tags "capacitor SMD 0402")
    (property "Author" "Antmicro")
    (property "Dielectric" "X7R")
    (property "License" "Apache-2.0")
    (property "MPN" "GRM155R71H103KA88D")
    (property "Manufacturer" "Murata")
    (property "Public" "False")
    (property "Sheetfile" "fpga-power-supply.kicad_sch")
    (property "Sheetname" "FPGA power supply")
    (property "Val" "10n")
    (property "Voltage" "50V")
    (property "ki_description" "SMD Multilayer Ceramic Capacitor, 10000 pF, 50 V, 0402 [1005 Metric], ± 10%, X7R, GRM Series")
    (property "ki_keywords" "0402, SMT, CAPACITOR, PASSIVE")
    (attr smd)
    (fp_text reference "C147" (at 22.8 -0.1 90) (layer "B.SilkS")
        (effects (font (size 0.7 0.7) (thickness 0.127)) (justify mirror))
    )
    (fp_text value "C_10n_0402" (at 0 -1.17 90) (layer "B.Fab")
        (effects (font (size 1 1) (thickness 0.15)) (justify mirror))
    )
    (fp_text user "Author: Antmicro" (at -0.939 -3.399 270) (layer "B.Fab") hide
        (effects (font (size 0.7 0.7) (thickness 0.15)) (justify left bottom mirror))
    )
    (fp_text user "License: Apache-2.0" (at -0.939 -5.799 270) (layer "B.Fab") hide
        (effects (font (size 0.7 0.7) (thickness 0.15)) (justify left bottom mirror))
    )
    (fp_text user "${REFERENCE}" (at 0 0 90) (layer "B.Fab")
        (effects (font (size 0.25 0.25) (thickness 0.04)) (justify mirror))
    )
    (fp_rect (start -0.925 0.47) (end 0.925 -0.47)
      (stroke (width 0.05) (type default)) (fill none) (layer "B.CrtYd"))
    (fp_line (start -0.494 -0.248) (end -0.494 0.25)
      (stroke (width 0.15) (type solid)) (layer "B.Fab"))
    (fp_line (start -0.494 0.25) (end 0.504 0.25)
      (stroke (width 0.15) (type solid)) (layer "B.Fab"))
    (fp_line (start 0.504 -0.248) (end -0.494 -0.248)
      (stroke (width 0.15) (type solid)) (layer "B.Fab"))
    (fp_line (start 0.504 0.25) (end 0.504 -0.248)
      (stroke (width 0.15) (type solid)) (layer "B.Fab"))
    (pad "1" smd roundrect (at -0.48 0 90) (size 0.59 0.64) (layers "B.Cu" "B.Paste" "B.Mask") (roundrect_rratio 0.25)
      (net 1 "GND") (pintype "passive"))
    (pad "2" smd roundrect (at 0.48 0 90) (size 0.59 0.64) (layers "B.Cu" "B.Paste" "B.Mask") (roundrect_rratio 0.25)
      (net 303 "/FPGA power supply/VCCA1") (pintype "passive"))
  )
)
